# BASEBOARD_FAB2 (Tioga Pass) — schematic netlist excerpt (pin names and nets, part order shuffled) for the footprints in the layout excerpt that follows; sources: Cadence DE-HDL packaged netlist, KiCad conversion of Wiwynn_Tioga_Pass_MB.brd

C2N22  CAP  10UF 6.3V 20% X6S  pkg 0603  page 130 : A = P3V3_STBY ; B = GND
R6P27  RES  4.02K 1% CHIP  pkg 0402  page 201 : A = VR_PVCCIN_CPU0_XADDR2 ; B = GND
C2M10  CAP  10UF 4V 20% X6S  pkg 0603LF  page 127 : A = P1V05_PCH_STBY_WM26_PLL ; B = GND

(kicad_pcb
	(version 20260206)
	(generator "pcbnew")
	(generator_version "10.0")
	(general
		(thickness 1.6)
		(legacy_teardrops no)
	)
	(paper "A4")
	(title_block
		(title "Wiwynn_Tioga_Pass_MB.brd")
		(comment 1 "Tioga Pass / footprints 3124-3126 of 4770")
	)
	(layers
		(0 "F.Cu" signal "TOP")
		(4 "In1.Cu" signal "L2GND")
		(6 "In2.Cu" signal "L3")
		(8 "In3.Cu" signal "L4GND")
		(10 "In4.Cu" signal "L5")
		(12 "In5.Cu" signal "L6GND")
		(14 "In6.Cu" signal "L7VCC")
		(16 "In7.Cu" signal "L8VCC")
		(18 "In8.Cu" signal "L9GND")
		(20 "In9.Cu" signal "L10")
		(22 "In10.Cu" signal "L11GND")
		(24 "In11.Cu" signal "L12")
		(26 "In12.Cu" signal "L13GND")
		(2 "B.Cu" signal "BOTTOM")
		(9 "F.Adhes" user "F.Adhesive")
		(11 "B.Adhes" user "B.Adhesive")
		(13 "F.Paste" user "Package Geometry/Pastemask Top")
		(15 "B.Paste" user "Package Geometry/Pastemask Bottom")
		(5 "F.SilkS" user "Ref Des/Silkscreen Top")
		(7 "B.SilkS" user "Ref Des/Silkscreen Bottom")
		(1 "F.Mask" user "Board Geometry/Soldermask Top")
		(3 "B.Mask" user "Board Geometry/Soldermask Bottom")
		(17 "Dwgs.User" user "User.Drawings")
		(19 "Cmts.User" user "User.Comments")
		(21 "Eco1.User" user "User.Eco1")
		(23 "Eco2.User" user "User.Eco2")
		(25 "Edge.Cuts" user "Board Geometry/Outline")
		(27 "Margin" user)
		(31 "F.CrtYd" user "Package Geometry/Place Bound Top")
		(29 "B.CrtYd" user "Package Geometry/Place Bound Bottom")
		(35 "F.Fab" user "Ref Des/Assembly Top")
		(33 "B.Fab" user "Ref Des/Assembly Bottom")
	)
	(footprint ""
		(layer "B.Cu")
		(at 185.039 -72.898)
		(property "Reference" "R6P27"
			(at 0 0 0)
			(layer "B.SilkS")
			(hide yes)
			(effects
				(font
					(size 1.27 1.27)
				)
				(justify mirror)
			)
		)
		(property "Value" ""
			(at 0 0 0)
			(layer "B.Fab")
			(effects
				(font
					(size 1.27 1.27)
				)
				(justify mirror)
			)
		)
		(duplicate_pad_numbers_are_jumpers no)
		(fp_rect
			(start -0.2794 0.9906)
			(end 0.2794 -0.1016)
			(stroke
				(width 0)
				(type default)
			)
			(fill no)
			(layer "B.CrtYd")
		)
		(fp_line
			(start -0.2794 -0.1016)
			(end 0.2794 -0.1016)
			(stroke
				(width 0.1)
				(type default)
			)
			(layer "B.Fab")
		)
		(fp_line
			(start -0.2794 0.9906)
			(end -0.2794 -0.1016)
			(stroke
				(width 0.1)
				(type default)
			)
			(layer "B.Fab")
		)
		(fp_line
			(start 0.2794 -0.1016)
			(end 0.2794 0.9906)
			(stroke
				(width 0.1)
				(type default)
			)
			(layer "B.Fab")
		)
		(fp_line
			(start 0.2794 0.9906)
			(end -0.2794 0.9906)
			(stroke
				(width 0.1)
				(type default)
			)
			(layer "B.Fab")
		)
		(pad "1" smd rect
			(at 0 0 180)
			(size 0.508 0.508)
			(layers "B.Cu" "B.Mask" "B.Paste")
			(net "VR_PVCCIN_CPU0_XADDR2")
		)
		(pad "2" smd rect
			(at 0 0.889 180)
			(size 0.508 0.508)
			(layers "B.Cu" "B.Mask" "B.Paste")
			(net "GND")
		)
		(zone
			(layer "B.Cu")
			(hatch none 0.5)
			(connect_pads
				(clearance 0)
			)
			(min_thickness 0.25)
			(keepout
				(tracks not_allowed)
				(vias allowed)
				(pads allowed)
				(copperpour not_allowed)
				(footprints allowed)
			)
			(placement
				(enabled no)
				(sheetname "")
			)
			(fill
				(thermal_gap 0.5)
				(thermal_bridge_width 0.5)
				(island_removal_mode 0)
			)
			(polygon
				(pts
					(xy 184.785 -72.263) (xy 185.293 -72.263) (xy 185.293 -72.644) (xy 184.785 -72.644)
				)
			)
		)
		(zone
			(layer "B.Cu")
			(hatch none 0.5)
			(connect_pads
				(clearance 0)
			)
			(min_thickness 0.25)
			(keepout
				(tracks allowed)
				(vias not_allowed)
				(pads allowed)
				(copperpour not_allowed)
				(footprints allowed)
			)
			(placement
				(enabled no)
				(sheetname "")
			)
			(fill
				(thermal_gap 0.5)
				(thermal_bridge_width 0.5)
				(island_removal_mode 0)
			)
			(polygon
				(pts
					(xy 184.785 -72.263) (xy 185.293 -72.263) (xy 185.293 -72.644) (xy 184.785 -72.644)
				)
			)
		)
	)
	(footprint ""
		(layer "B.Cu")
		(at 405.2062 -105.8545 180)
		(property "Reference" "C2N22"
			(at 0 0 0)
			(layer "B.SilkS")
			(hide yes)
			(effects
				(font
					(size 1.27 1.27)
				)
				(justify mirror)
			)
		)
		(property "Value" ""
			(at 0 0 0)
			(layer "B.Fab")
			(effects
				(font
					(size 1.27 1.27)
				)
				(justify mirror)
			)
		)
		(duplicate_pad_numbers_are_jumpers no)
		(fp_poly
			(pts
				(xy 0.4953 -0.2032) (xy -0.4953 -0.2032) (xy -0.4953 1.6002) (xy 0.4953 1.6002)
			)
			(stroke
				(width 0)
				(type default)
			)
			(fill no)
			(layer "B.CrtYd")
		)
		(fp_line
			(start 0.4953 1.6002)
			(end 0.4953 -0.2032)
			(stroke
				(width 0.1)
				(type default)
			)
			(layer "B.Fab")
		)
		(fp_line
			(start 0.4953 -0.2032)
			(end -0.4953 -0.2032)
			(stroke
				(width 0.1)
				(type default)
			)
			(layer "B.Fab")
		)
		(fp_line
			(start -0.4953 1.6002)
			(end 0.4953 1.6002)
			(stroke
				(width 0.1)
				(type default)
			)
			(layer "B.Fab")
		)
		(fp_line
			(start -0.4953 -0.2032)
			(end -0.4953 1.6002)
			(stroke
				(width 0.1)
				(type default)
			)
			(layer "B.Fab")
		)
		(pad "1" smd rect
			(at 0 0)
			(size 0.762 0.889)
			(layers "B.Cu" "B.Mask" "B.Paste")
			(net "P3V3_STBY")
		)
		(pad "2" smd rect
			(at 0 1.397)
			(size 0.762 0.889)
			(layers "B.Cu" "B.Mask" "B.Paste")
			(net "GND")
		)
		(zone
			(layer "B.Cu")
			(hatch none 0.5)
			(connect_pads
				(clearance 0)
			)
			(min_thickness 0.25)
			(keepout
				(tracks not_allowed)
				(vias allowed)
				(pads allowed)
				(copperpour not_allowed)
				(footprints allowed)
			)
			(placement
				(enabled no)
				(sheetname "")
			)
			(fill
				(thermal_gap 0.5)
				(thermal_bridge_width 0.5)
				(island_removal_mode 0)
			)
			(polygon
				(pts
					(xy 404.8252 -106.299) (xy 405.5872 -106.299) (xy 405.5872 -106.807) (xy 404.8252 -106.807)
				)
			)
		)
	)
	(footprint ""
		(layer "B.Cu")
		(at 408.432 -119.391684)
		(property "Reference" "C2M10"
			(at 0 0 0)
			(layer "B.SilkS")
			(hide yes)
			(effects
				(font
					(size 1.27 1.27)
				)
				(justify mirror)
			)
		)
		(property "Value" ""
			(at 0 0 0)
			(layer "B.Fab")
			(effects
				(font
					(size 1.27 1.27)
				)
				(justify mirror)
			)
		)
		(duplicate_pad_numbers_are_jumpers no)
		(fp_poly
			(pts
				(xy 0.4953 -0.2032) (xy -0.4953 -0.2032) (xy -0.4953 1.6002) (xy 0.4953 1.6002)
			)
			(stroke
				(width 0)
				(type default)
			)
			(fill no)
			(layer "B.CrtYd")
		)
		(fp_line
			(start -0.4953 -0.2032)
			(end -0.4953 1.6002)
			(stroke
				(width 0.1)
				(type default)
			)
			(layer "B.Fab")
		)
		(fp_line
			(start -0.4953 1.6002)
			(end 0.4953 1.6002)
			(stroke
				(width 0.1)
				(type default)
			)
			(layer "B.Fab")
		)
		(fp_line
			(start 0.4953 -0.2032)
			(end -0.4953 -0.2032)
			(stroke
				(width 0.1)
				(type default)
			)
			(layer "B.Fab")
		)
		(fp_line
			(start 0.4953 1.6002)
			(end 0.4953 -0.2032)
			(stroke
				(width 0.1)
				(type default)
			)
			(layer "B.Fab")
		)
		(pad "1" smd rect
			(at 0 0 180)
			(size 0.762 0.889)
			(layers "B.Cu" "B.Mask" "B.Paste")
			(net "P1V05_PCH_STBY_WM26_PLL")
		)
		(pad "2" smd rect
			(at 0 1.397 180)
			(size 0.762 0.889)
			(layers "B.Cu" "B.Mask" "B.Paste")
			(net "GND")
		)
		(zone
			(layer "B.Cu")
			(hatch none 0.5)
			(connect_pads
				(clearance 0)
			)
			(min_thickness 0.25)
			(keepout
				(tracks not_allowed)
				(vias allowed)
				(pads allowed)
				(copperpour not_allowed)
				(footprints allowed)
			)
			(placement
				(enabled no)
				(sheetname "")
			)
			(fill
				(thermal_gap 0.5)
				(thermal_bridge_width 0.5)
				(island_removal_mode 0)
			)
			(polygon
				(pts
					(xy 408.813 -118.947184) (xy 408.051 -118.947184) (xy 408.051 -118.439184) (xy 408.813 -118.439184)
				)
			)
		)
	)
)
